FILE_TYPE = MULTI_PHYS_TABLE;

PART 'DIODE_2F'
CLASS=DISCRETE

{========================================================================================}
:CLS_PN          = JEDEC_TYPE          | ALT_SYMBOLS           | DESCRIPTION                                        | CPN_STATUS ;
{========================================================================================}
 'G122-10017-01' = 'SMC_CR_271X232_V1' | '(SMC_CR_271X232_V1)' | 'DIO,MBRS540T3G,SCHOTKY_REC_5A,40V,SMC'            | ''        
 'G122-10103-01' = 'SMC_CR_169X103_V2' | '(SMC_CR_169X103_V2)' | 'DIO,SCHOTTKY,B140,40V,1A,SMA'                     | ''        
 'G122-10104-01' = 'SMC_CR_167X105_V4' | '(SMC_CR_167X105_V4)' | 'DIO,SCHOTTKY,SS1H10,100V/1A,SMA,ROHS COMPLIANT'   | ''        
 'G122-10027-01' = 'SOD123'            | '(SOD123)'            | 'DIO,SCHOTTKY,1N5819HW,40V,1A,SOD123,SMD'          | ''        
 'G122-00007-01' = 'SMC_CR_270X230'    | '(SMC_CR_270X230)'    | 'DIO,MBRS340T3,SCHOTKY_REC,40V,SMC'                | ''        
 'G122-10110-01' = 'SOD123_V1'         | '(SOD123_V1)'         | 'DIO,B0540W,SCHOTTKY,40V,0.5A,SOD123'              | ''        
 'G122-10113-01' = 'SMC_CR_167X105_V4' | '(SMC_CR_167X105_V4)' | 'DIO,SS15,SCHOTTKY,50V,1A,DO214AC/SMA'             | ''        
 'G122-10132-01' = 'SMC_CR_110X070'    | '(SMC_CR_110X070)'    | 'DIO,DFLS1100-7,RECTIFIER,100V,1A,POWERDI123'      | ''        
 'G122-10138-01' = 'SMC_CR_106X065'    | '(SMC_CR_106X065)'    | 'DIO,SCHOTTKY,MBR2H100SF,100V,2A,SOD-123'          | ''        
 'G122-10056-01' = 'SMC_CR_150X098'    | '(SMC_CR_150X098)'    | 'DIO,SCHOTTKY,2A,30V,SOD-128'                      | ''        
 'G122-10042-01' = 'SMC_CR_169X103_V2' | '(SMC_CR_169X103_V2)' | 'DIODE,SCHOTTKY,B320A, 20V/3A,SMA,ROHS COMPLIANT'  | ''        
 'G122-10161-01' = 'SMC_CR_106X065'    | '(SMC_CR_106X065)'    | 'DIO, SCHOTTKY, MBR230LSFT1G, 30V, 2A, SOD-123FL'  | ''        
 'G122-10162-01' = 'SMC_CR_169X102_V1' | '(SMC_CR_169X102_V1)' | 'DIO,SS1200, SCHOTTKY,1A,200V,SMA'                 | ''        
 'G122-10166-01' = 'TO247_2'           | '(TO247_2)'           | 'DIO,C3D10170H,SIC, SCHOTTKY,14.4A,1700V,TO247'    | ''        
 'G122-10095-01' = 'SMC_CR_040X024'    | '(SMC_CR_040X024)'    | 'DIO,SCHOTTKY BARRIER DIODE, 30V, 200MA,DFN1006'   | ''        
 'G122-00014-01' = 'SOD123V3'          | '(SOD123V3)'          | 'DIO,MBR0530,SCHOTTKY,0.45V,0.5A,SOD123'           | ''        
 'G122-10185-01' = 'SMC_CR_150X098'    | '(SMC_CR_150X098)'    | 'DIO,SCHOTTKY,5A,30V,VF=0.36V,SOD128'              | ''        
 'G122-10186-01' = 'SMC_CR_067X049_V1' | '(SMC_CR_067X049_V1)' | 'DIO,SCHOTTKY,20V,1A,SOD323'                       | ''        
 'A122-00006-AW' = 'SMC_CR_106X065'    | '(SMC_CR_106X065)'    | 'DIO,SCHOTTKY,MBR120VLSFT1G,20V,1A,SOD-123FL'      | ''        
 'A122-00007-AW' = 'SOD523_V2'         | '(SOD523_V2)'         | 'DIO,ESD PROTECTION,PESD5Z3.3,115,3.3V,20A,SOD523' | ''        
 'A122-10027-IB' = 'SOD123'            | '(SOD123)'            | 'DIO,SCHOTTKY,40V,1A,SOD123,SMD'                   | ''        
 'G122-10027-02' = 'SOD123'            | '(SOD123)'            | 'DIO,SCHOTTKY,40V,1A,SOD123,SMD'                   | ''        
 'G122-10042-02' = 'SMC_CR_169X103_V2' | '(SMC_CR_169X103_V2)' | 'DIODE,SCHOTTKY,B320A,20V/3A,SMA,ROHS COMPLIANT'   | ''        
 'G122-10186-02' = 'SMC_CR_067X049_V1' | '(SMC_CR_067X049_V1)' | 'DIO,SCHOTTKY,20V,1A,SOD323'                       | ''        

END_PART

END.

